# T6G (Grand Teton) — schematic netlist excerpt (pin names and nets, part order shuffled) for the footprints in the layout excerpt that follows; sources: Cadence DE-HDL packaged netlist, KiCad conversion of 04192023_DAF0TMB3IC0_F0TG_MB_C_brd_V02_OCP.brd

R6142  Q_RES  1K 1% CHIP  pkg 0402LF  page 84 : A = FM_BOARD_BMC_SKU_ID3 ; B = GND
R1324  Q_RES  0.002 1% CHIP  pkg 2512LF  page 357 : A = P12V_OCP_SFF_R ; B = P12V_OCP_SFF
R3354  Q_RES  0 5% CHIP  pkg 0402LF  page 55 : A = CLK_100M_CPU1_CLK01_R_DP ; B = CLK_100M_CPU1_CLK01_DP

(kicad_pcb
	(version 20260206)
	(generator "pcbnew")
	(generator_version "10.0")
	(general
		(thickness 1.6)
		(legacy_teardrops no)
	)
	(paper "A4")
	(title_block
		(title "04192023_DAF0TMB3IC0_F0TG_MB_C_brd_V02_OCP.brd")
		(comment 1 "Grand Teton / footprints 4734-4736 of 8354")
	)
	(layers
		(0 "F.Cu" signal "TOP")
		(4 "In1.Cu" signal "GND")
		(6 "In2.Cu" signal "IN1")
		(8 "In3.Cu" signal "GND1")
		(10 "In4.Cu" signal "IN2")
		(12 "In5.Cu" signal "GND2")
		(14 "In6.Cu" signal "IN3")
		(16 "In7.Cu" signal "GND3")
		(18 "In8.Cu" signal "VCC")
		(20 "In9.Cu" signal "VCC1")
		(22 "In10.Cu" signal "GND4")
		(24 "In11.Cu" signal "IN4")
		(26 "In12.Cu" signal "GND5")
		(28 "In13.Cu" signal "IN5")
		(30 "In14.Cu" signal "GND6")
		(32 "In15.Cu" signal "IN6")
		(34 "In16.Cu" signal "GND7")
		(2 "B.Cu" signal "BOTTOM")
		(9 "F.Adhes" user "F.Adhesive")
		(11 "B.Adhes" user "B.Adhesive")
		(13 "F.Paste" user "Package Geometry/Pastemask Top")
		(15 "B.Paste" user "Package Geometry/Pastemask Bottom")
		(5 "F.SilkS" user "Ref Des/Silkscreen Top")
		(7 "B.SilkS" user "Ref Des/Silkscreen Bottom")
		(1 "F.Mask" user "Board Geometry/Soldermask Top")
		(3 "B.Mask" user "Board Geometry/Soldermask Bottom")
		(17 "Dwgs.User" user "User.Drawings")
		(19 "Cmts.User" user "User.Comments")
		(21 "Eco1.User" user "User.Eco1")
		(23 "Eco2.User" user "User.Eco2")
		(25 "Edge.Cuts" user "Board Geometry/Outline")
		(27 "Margin" user)
		(31 "F.CrtYd" user "Package Geometry/Place Bound Top")
		(29 "B.CrtYd" user "Package Geometry/Place Bound Bottom")
		(35 "F.Fab" user "Ref Des/Assembly Top")
		(33 "B.Fab" user "Ref Des/Assembly Bottom")
	)
	(footprint ""
		(layer "F.Cu")
		(at 153.277824 -191.358266 -90)
		(property "Reference" "R3354"
			(at 0 0 270)
			(layer "F.SilkS")
			(hide yes)
			(effects
				(font
					(size 1.27 1.27)
				)
			)
		)
		(property "Value" ""
			(at 0 0 270)
			(layer "F.Fab")
			(effects
				(font
					(size 1.27 1.27)
				)
			)
		)
		(duplicate_pad_numbers_are_jumpers no)
		(fp_line
			(start -0.7874 0.4064)
			(end -0.7874 -0.061976)
			(stroke
				(width 0.1524)
				(type default)
			)
			(layer "F.SilkS")
		)
		(fp_line
			(start 0.7874 0.4064)
			(end -0.7874 0.4064)
			(stroke
				(width 0.1524)
				(type default)
			)
			(layer "F.SilkS")
		)
		(fp_line
			(start 0.7874 -0.061976)
			(end 0.7874 0.4064)
			(stroke
				(width 0.1524)
				(type default)
			)
			(layer "F.SilkS")
		)
		(fp_line
			(start -0.386334 -0.4064)
			(end 0.324866 -0.4064)
			(stroke
				(width 0.1524)
				(type default)
			)
			(layer "F.SilkS")
		)
		(fp_line
			(start -0.67945 0.3048)
			(end -0.67945 -0.305054)
			(stroke
				(width 0.1)
				(type default)
			)
			(layer "F.Fab")
		)
		(fp_line
			(start -0.12065 0.3048)
			(end -0.67945 0.3048)
			(stroke
				(width 0.1)
				(type default)
			)
			(layer "F.Fab")
		)
		(fp_line
			(start 0.120396 0.3048)
			(end 0.120396 0.2794)
			(stroke
				(width 0.1)
				(type default)
			)
			(layer "F.Fab")
		)
		(fp_line
			(start 0.67945 0.3048)
			(end 0.120396 0.3048)
			(stroke
				(width 0.1)
				(type default)
			)
			(layer "F.Fab")
		)
		(fp_line
			(start -0.12065 0.2794)
			(end -0.12065 0.3048)
			(stroke
				(width 0.1)
				(type default)
			)
			(layer "F.Fab")
		)
		(fp_line
			(start 0.120396 0.2794)
			(end -0.12065 0.2794)
			(stroke
				(width 0.1)
				(type default)
			)
			(layer "F.Fab")
		)
		(fp_line
			(start -0.12065 -0.2794)
			(end 0.12065 -0.2794)
			(stroke
				(width 0.1)
				(type default)
			)
			(layer "F.Fab")
		)
		(fp_line
			(start 0.12065 -0.2794)
			(end 0.12065 -0.3048)
			(stroke
				(width 0.1)
				(type default)
			)
			(layer "F.Fab")
		)
		(fp_line
			(start 0.12065 -0.3048)
			(end 0.67945 -0.3048)
			(stroke
				(width 0.1)
				(type default)
			)
			(layer "F.Fab")
		)
		(fp_line
			(start 0.67945 -0.3048)
			(end 0.67945 0.3048)
			(stroke
				(width 0.1)
				(type default)
			)
			(layer "F.Fab")
		)
		(fp_line
			(start -0.67945 -0.305054)
			(end -0.12065 -0.305054)
			(stroke
				(width 0.1)
				(type default)
			)
			(layer "F.Fab")
		)
		(fp_line
			(start -0.12065 -0.305054)
			(end -0.12065 -0.2794)
			(stroke
				(width 0.1)
				(type default)
			)
			(layer "F.Fab")
		)
		(pad "1" smd circle
			(at -0.40005 0 270)
			(size 0 0)
			(layers "F.Cu" "F.Mask" "F.Paste")
			(net "CLK_100M_CPU1_CLK01_R_DP")
		)
		(pad "2" smd circle
			(at 0.40005 0 270)
			(size 0 0)
			(layers "F.Cu" "F.Mask" "F.Paste")
			(net "CLK_100M_CPU1_CLK01_DP")
		)
	)
	(footprint ""
		(layer "F.Cu")
		(at 163.734496 -117.310662 180)
		(property "Reference" "R6142"
			(at 0 0 180)
			(layer "F.SilkS")
			(hide yes)
			(effects
				(font
					(size 1.27 1.27)
				)
			)
		)
		(property "Value" ""
			(at 0 0 180)
			(layer "F.Fab")
			(effects
				(font
					(size 1.27 1.27)
				)
			)
		)
		(duplicate_pad_numbers_are_jumpers no)
		(fp_line
			(start 0.7874 0.4064)
			(end -0.7874 0.4064)
			(stroke
				(width 0.1524)
				(type default)
			)
			(layer "F.SilkS")
		)
		(fp_line
			(start 0.7874 -0.4064)
			(end 0.7874 0.4064)
			(stroke
				(width 0.1524)
				(type default)
			)
			(layer "F.SilkS")
		)
		(fp_line
			(start -0.7874 0.4064)
			(end -0.7874 -0.4064)
			(stroke
				(width 0.1524)
				(type default)
			)
			(layer "F.SilkS")
		)
		(fp_line
			(start -0.7874 -0.4064)
			(end 0.7874 -0.4064)
			(stroke
				(width 0.1524)
				(type default)
			)
			(layer "F.SilkS")
		)
		(fp_line
			(start 0.67945 0.3048)
			(end 0.120396 0.3048)
			(stroke
				(width 0.1)
				(type default)
			)
			(layer "F.Fab")
		)
		(fp_line
			(start 0.67945 -0.3048)
			(end 0.67945 0.3048)
			(stroke
				(width 0.1)
				(type default)
			)
			(layer "F.Fab")
		)
		(fp_line
			(start 0.12065 -0.2794)
			(end 0.12065 -0.3048)
			(stroke
				(width 0.1)
				(type default)
			)
			(layer "F.Fab")
		)
		(fp_line
			(start 0.12065 -0.3048)
			(end 0.67945 -0.3048)
			(stroke
				(width 0.1)
				(type default)
			)
			(layer "F.Fab")
		)
		(fp_line
			(start 0.120396 0.3048)
			(end 0.120396 0.2794)
			(stroke
				(width 0.1)
				(type default)
			)
			(layer "F.Fab")
		)
		(fp_line
			(start 0.120396 0.2794)
			(end -0.12065 0.2794)
			(stroke
				(width 0.1)
				(type default)
			)
			(layer "F.Fab")
		)
		(fp_line
			(start -0.12065 0.3048)
			(end -0.67945 0.3048)
			(stroke
				(width 0.1)
				(type default)
			)
			(layer "F.Fab")
		)
		(fp_line
			(start -0.12065 0.2794)
			(end -0.12065 0.3048)
			(stroke
				(width 0.1)
				(type default)
			)
			(layer "F.Fab")
		)
		(fp_line
			(start -0.12065 -0.2794)
			(end 0.12065 -0.2794)
			(stroke
				(width 0.1)
				(type default)
			)
			(layer "F.Fab")
		)
		(fp_line
			(start -0.12065 -0.305054)
			(end -0.12065 -0.2794)
			(stroke
				(width 0.1)
				(type default)
			)
			(layer "F.Fab")
		)
		(fp_line
			(start -0.67945 0.3048)
			(end -0.67945 -0.305054)
			(stroke
				(width 0.1)
				(type default)
			)
			(layer "F.Fab")
		)
		(fp_line
			(start -0.67945 -0.305054)
			(end -0.12065 -0.305054)
			(stroke
				(width 0.1)
				(type default)
			)
			(layer "F.Fab")
		)
		(pad "1" smd circle
			(at -0.40005 0 180)
			(size 0 0)
			(layers "F.Cu" "F.Mask" "F.Paste")
			(net "FM_BOARD_BMC_SKU_ID3")
		)
		(pad "2" smd circle
			(at 0.40005 0 180)
			(size 0 0)
			(layers "F.Cu" "F.Mask" "F.Paste")
			(net "GND")
		)
	)
	(footprint ""
		(layer "F.Cu")
		(at 441.863226 -19.059906)
		(property "Reference" "R1324"
			(at 0.350774 2.703576 0)
			(unlocked yes)
			(layer "F.SilkS")
			(effects
				(font
					(size 0.7874 0.5842)
					(thickness 0.1524)
				)
				(justify left)
			)
		)
		(property "Value" ""
			(at 0 0 0)
			(layer "F.Fab")
			(effects
				(font
					(size 1.27 1.27)
				)
			)
		)
		(duplicate_pad_numbers_are_jumpers no)
		(fp_line
			(start -3.937508 -1.8796)
			(end -3.937508 1.8796)
			(stroke
				(width 0.1524)
				(type default)
			)
			(layer "F.SilkS")
		)
		(fp_line
			(start -3.937508 1.8796)
			(end 3.937508 1.8796)
			(stroke
				(width 0.1524)
				(type default)
			)
			(layer "F.SilkS")
		)
		(fp_line
			(start 3.937508 -1.8796)
			(end -3.937508 -1.8796)
			(stroke
				(width 0.1524)
				(type default)
			)
			(layer "F.SilkS")
		)
		(fp_line
			(start 3.937508 1.8796)
			(end 3.937508 -1.8796)
			(stroke
				(width 0.1524)
				(type default)
			)
			(layer "F.SilkS")
		)
		(fp_line
			(start -3.275076 -1.674876)
			(end -3.275076 1.674876)
			(stroke
				(width 0.1)
				(type default)
			)
			(layer "F.Fab")
		)
		(fp_line
			(start -3.275076 1.674876)
			(end 3.275076 1.674876)
			(stroke
				(width 0.1)
				(type default)
			)
			(layer "F.Fab")
		)
		(fp_line
			(start 3.275076 -1.674876)
			(end -3.275076 -1.674876)
			(stroke
				(width 0.1)
				(type default)
			)
			(layer "F.Fab")
		)
		(fp_line
			(start 3.275076 1.674876)
			(end 3.275076 -1.674876)
			(stroke
				(width 0.1)
				(type default)
			)
			(layer "F.Fab")
		)
		(pad "1" smd rect
			(at -2.350008 0)
			(size 2.921 3.5052)
			(layers "F.Cu" "F.Mask" "F.Paste")
			(net "P12V_OCP_SFF_R")
		)
		(pad "2" smd rect
			(at 2.350008 0)
			(size 2.921 3.5052)
			(layers "F.Cu" "F.Mask" "F.Paste")
			(net "P12V_OCP_SFF")
		)
	)
)
